(kicad_pcb
	(version 20221018)
	(generator pcbnew)
	(general
    (thickness 1.562)
  )
	(paper "A4")
	(title_block
    (title "Thunderbolt PCIe Adaper")
    (date "2024-07-09")
    (rev "1.0.3")
    (comment 1 "www.antmicro.com")
    (comment 2 "Antmicro Ltd.")
		(comment 9 "footprints 151-159 of 271")
	)
	(layers
    (0 "F.Cu" signal)
    (1 "In1.Cu" signal)
    (2 "In2.Cu" signal)
    (3 "In3.Cu" signal)
    (4 "In4.Cu" signal)
    (31 "B.Cu" signal)
    (32 "B.Adhes" user "B.Adhesive")
    (33 "F.Adhes" user "F.Adhesive")
    (34 "B.Paste" user)
    (35 "F.Paste" user)
    (36 "B.SilkS" user "B.Silkscreen")
    (37 "F.SilkS" user "F.Silkscreen")
    (38 "B.Mask" user)
    (39 "F.Mask" user)
    (40 "Dwgs.User" user "User.Drawings")
    (41 "Cmts.User" user "User.Comments")
    (42 "Eco1.User" user "User.Eco1")
    (43 "Eco2.User" user "User.Eco2")
    (44 "Edge.Cuts" user)
    (45 "Margin" user)
    (46 "B.CrtYd" user "B.Courtyard")
    (47 "F.CrtYd" user "F.Courtyard")
    (48 "B.Fab" user)
    (49 "F.Fab" user)
  )
	(footprint "antmicro-footprints:C_0402_1005Metric" (layer "B.Cu")
    (at 129.46 80.34 -90)
    (descr "Capacitor SMD 0402")
    (tags "capacitor SMD 0402")
    (property "Author" "Antmicro")
    (property "Dielectric" "X5R")
    (property "License" "Apache-2.0")
    (property "MPN" "GRM155R61H104KE14D")
    (property "Manufacturer" "Murata")
    (property "Sheetfile" "tb-power.kicad_sch")
    (property "Sheetname" "Thunderbolt Controller - Power")
    (property "Val" "100n")
    (property "Voltage" "50V")
    (property "ki_description" "SMD Multilayer Ceramic Capacitor, 0.1 µF, 50 V, 0402 [1005 Metric], ± 10%, X5R, GRM Series")
    (property "ki_keywords" "0402, SMT, CAPACITOR, PASSIVE, CERAMIC, MLCC")
    (attr smd)
    (fp_text reference "C97" (at -0.965 2.537 90) (layer "B.SilkS")
        (effects (font (size 0.7 0.7) (thickness 0.15)) (justify left bottom mirror))
    )
    (fp_text value "C_100n_0402" (at -1.022927 -2.155213 90) (layer "B.Fab")
        (effects (font (size 0.7 0.7) (thickness 0.15)) (justify left bottom mirror))
    )
    (fp_text user "License: Apache-2.0" (at -0.939 -5.799 90) (layer "B.Fab") hide
        (effects (font (size 0.7 0.7) (thickness 0.15)) (justify left bottom mirror))
    )
    (fp_text user "${REFERENCE}" (at -0.939 -4.599 90) (layer "B.Fab") hide
        (effects (font (size 0.7 0.7) (thickness 0.15)) (justify left bottom mirror))
    )
    (fp_text user "Author: Antmicro" (at -0.939 -3.399 90) (layer "B.Fab") hide
        (effects (font (size 0.7 0.7) (thickness 0.15)) (justify left bottom mirror))
    )
    (fp_rect (start -0.925 0.47) (end 0.925 -0.47)
      (stroke (width 0.05) (type default)) (fill none) (layer "B.CrtYd"))
    (fp_line (start -0.494 -0.248) (end -0.494 0.25)
      (stroke (width 0.15) (type solid)) (layer "B.Fab"))
    (fp_line (start -0.494 0.25) (end 0.504 0.25)
      (stroke (width 0.15) (type solid)) (layer "B.Fab"))
    (fp_line (start 0.504 -0.248) (end -0.494 -0.248)
      (stroke (width 0.15) (type solid)) (layer "B.Fab"))
    (fp_line (start 0.504 0.25) (end 0.504 -0.248)
      (stroke (width 0.15) (type solid)) (layer "B.Fab"))
    (pad "1" smd roundrect (at -0.48 0 270) (size 0.59 0.64) (layers "B.Cu" "B.Paste" "B.Mask") (roundrect_rratio 0.25)
      (net 1 "GND") (pintype "passive"))
    (pad "2" smd roundrect (at 0.48 0 270) (size 0.59 0.64) (layers "B.Cu" "B.Paste" "B.Mask") (roundrect_rratio 0.25)
      (net 2 "3V3_SYS") (pintype "passive"))
  )
	(footprint "antmicro-footprints:R_0402_1005Metric" (layer "B.Cu")
    (at 107.425 84.17 90)
    (descr "Resistor SMD 0402")
    (tags "resistor SMD 0402")
    (property "Author" "Antmicro")
    (property "Current" "1A")
    (property "License" "Apache-2.0")
    (property "MPN" "ERJ2GE0R00X")
    (property "Manufacturer" "Panasonic")
    (property "Sheetfile" "power.kicad_sch")
    (property "Sheetname" "Power")
    (property "Tolerance" "")
    (property "Val" "0R")
    (property "ki_description" "SMD Chip Resistor, Jumper, 0 ohm, 100 mW, 0402 [1005 Metric], Thick Film, General Purpose")
    (property "ki_keywords" "0402, SMT, RESISTOR, PASSIVE")
    (attr smd)
    (fp_text reference "R13" (at 0.985 -0.618 270) (layer "B.SilkS")
        (effects (font (size 0.7 0.7) (thickness 0.15)) (justify left bottom mirror))
    )
    (fp_text value "R_0R_0402" (at -1.011843 -1.772047 270) (layer "B.Fab")
        (effects (font (size 0.7 0.7) (thickness 0.15)) (justify left bottom mirror))
    )
    (fp_text user "Author: Antmicro" (at -0.95 -4.169 270) (layer "B.Fab") hide
        (effects (font (size 0.7 0.7) (thickness 0.15)) (justify left bottom mirror))
    )
    (fp_text user "License: Apache-2.0" (at -0.95 -5.169 270) (layer "B.Fab") hide
        (effects (font (size 0.7 0.7) (thickness 0.15)) (justify left bottom mirror))
    )
    (fp_text user "${REFERENCE}" (at -0.95 -3.168 270) (layer "B.Fab") hide
        (effects (font (size 0.7 0.7) (thickness 0.15)) (justify left bottom mirror))
    )
    (fp_rect (start -0.925 0.47) (end 0.925 -0.47)
      (stroke (width 0.05) (type default)) (fill none) (layer "B.CrtYd"))
    (fp_rect (start -0.5 0.25) (end 0.5 -0.25)
      (stroke (width 0.15) (type solid)) (fill none) (layer "B.Fab"))
    (pad "1" smd roundrect (at -0.48 0 90) (size 0.59 0.64) (layers "B.Cu" "B.Paste" "B.Mask") (roundrect_rratio 0.25)
      (net 5 "Net-(U1-VREF)") (pintype "passive"))
    (pad "2" smd roundrect (at 0.48 0 90) (size 0.59 0.64) (layers "B.Cu" "B.Paste" "B.Mask") (roundrect_rratio 0.25)
      (net 148 "Net-(U1-LOADEN)") (pintype "passive"))
  )
	(footprint "antmicro-footprints:R_0402_1005Metric" (layer "B.Cu")
    (at 145.62 76.96)
    (descr "Resistor SMD 0402")
    (tags "resistor SMD 0402")
    (property "Author" "Antmicro")
    (property "License" "Apache-2.0")
    (property "MPN" "CR0402-FX-1004GLF")
    (property "Manufacturer" "Bourns")
    (property "Sheetfile" "tb.kicad_sch")
    (property "Sheetname" "TB Controller")
    (property "Tolerance" "1%")
    (property "Val" "1M")
    (property "ki_description" "SMD Chip Resistor, 1 Mohm, ± 1%, 62.5 mW, 0402 [1005 Metric], Thick Film, General Purpose")
    (property "ki_keywords" "0402, SMT, RESISTOR, PASSIVE")
    (attr smd)
    (fp_text reference "R55" (at 3.097 0.383 180) (layer "B.SilkS")
        (effects (font (size 0.7 0.7) (thickness 0.15)) (justify left bottom mirror))
    )
    (fp_text value "R_1M_0402" (at -1.011843 -1.772047 180) (layer "B.Fab")
        (effects (font (size 0.7 0.7) (thickness 0.15)) (justify left bottom mirror))
    )
    (fp_text user "License: Apache-2.0" (at -0.95 -5.169 180) (layer "B.Fab") hide
        (effects (font (size 0.7 0.7) (thickness 0.15)) (justify left bottom mirror))
    )
    (fp_text user "Author: Antmicro" (at -0.95 -4.169 180) (layer "B.Fab") hide
        (effects (font (size 0.7 0.7) (thickness 0.15)) (justify left bottom mirror))
    )
    (fp_text user "${REFERENCE}" (at -0.95 -3.168 180) (layer "B.Fab") hide
        (effects (font (size 0.7 0.7) (thickness 0.15)) (justify left bottom mirror))
    )
    (fp_rect (start -0.925 0.47) (end 0.925 -0.47)
      (stroke (width 0.05) (type default)) (fill none) (layer "B.CrtYd"))
    (fp_rect (start -0.5 0.25) (end 0.5 -0.25)
      (stroke (width 0.15) (type solid)) (fill none) (layer "B.Fab"))
    (pad "1" smd roundrect (at -0.48 0) (size 0.59 0.64) (layers "B.Cu" "B.Paste" "B.Mask") (roundrect_rratio 0.25)
      (net 1 "GND") (pintype "passive"))
    (pad "2" smd roundrect (at 0.48 0) (size 0.59 0.64) (layers "B.Cu" "B.Paste" "B.Mask") (roundrect_rratio 0.25)
      (net 67 "LSX_R2P") (pintype "passive"))
  )
	(footprint "antmicro-footprints:R_0402_1005Metric" (layer "B.Cu")
    (at 139.275 66.82 -90)
    (descr "Resistor SMD 0402")
    (tags "resistor SMD 0402")
    (property "Author" "Antmicro")
    (property "License" "Apache-2.0")
    (property "MPN" "CR0402-FX-2201GLF")
    (property "Manufacturer" "Bourns")
    (property "Sheetfile" "tb.kicad_sch")
    (property "Sheetname" "TB Controller")
    (property "Tolerance" "1%")
    (property "Val" "2k2")
    (property "ki_description" "SMD Chip Resistor, 2.2 kohm, ± 1%, 62.5 mW, 0402 [1005 Metric], Thick Film, General Purpose")
    (property "ki_keywords" "0402, SMT, RESISTOR, PASSIVE")
    (attr smd)
    (fp_text reference "R62" (at -3.066 -0.416 90) (layer "B.SilkS")
        (effects (font (size 0.7 0.7) (thickness 0.15)) (justify left bottom mirror))
    )
    (fp_text value "R_2k2_0402" (at -1.011843 -1.772047 90) (layer "B.Fab")
        (effects (font (size 0.7 0.7) (thickness 0.15)) (justify left bottom mirror))
    )
    (fp_text user "Author: Antmicro" (at -0.95 -4.169 90) (layer "B.Fab") hide
        (effects (font (size 0.7 0.7) (thickness 0.15)) (justify left bottom mirror))
    )
    (fp_text user "License: Apache-2.0" (at -0.95 -5.169 90) (layer "B.Fab") hide
        (effects (font (size 0.7 0.7) (thickness 0.15)) (justify left bottom mirror))
    )
    (fp_text user "${REFERENCE}" (at -0.95 -3.168 90) (layer "B.Fab") hide
        (effects (font (size 0.7 0.7) (thickness 0.15)) (justify left bottom mirror))
    )
    (fp_rect (start -0.925 0.47) (end 0.925 -0.47)
      (stroke (width 0.05) (type default)) (fill none) (layer "B.CrtYd"))
    (fp_rect (start -0.5 0.25) (end 0.5 -0.25)
      (stroke (width 0.15) (type solid)) (fill none) (layer "B.Fab"))
    (pad "1" smd roundrect (at -0.48 0 270) (size 0.59 0.64) (layers "B.Cu" "B.Paste" "B.Mask") (roundrect_rratio 0.25)
      (net 1 "GND") (pintype "passive"))
    (pad "2" smd roundrect (at 0.48 0 270) (size 0.59 0.64) (layers "B.Cu" "B.Paste" "B.Mask") (roundrect_rratio 0.25)
      (net 176 "Net-(U4C-DPSNK1_DDC_DATA)") (pintype "passive"))
  )
	(footprint "antmicro-footprints:C_0402_1005Metric" (layer "B.Cu")
    (at 142.15 76.43 90)
    (descr "Capacitor SMD 0402")
    (tags "capacitor SMD 0402")
    (property "Author" "Antmicro")
    (property "Dielectric" "X5R")
    (property "License" "Apache-2.0")
    (property "MPN" "GRM155R61H104KE14D")
    (property "Manufacturer" "Murata")
    (property "Sheetfile" "tb-power.kicad_sch")
    (property "Sheetname" "Thunderbolt Controller - Power")
    (property "Val" "100n")
    (property "Voltage" "50V")
    (property "ki_description" "SMD Multilayer Ceramic Capacitor, 0.1 µF, 50 V, 0402 [1005 Metric], ± 10%, X5R, GRM Series")
    (property "ki_keywords" "0402, SMT, CAPACITOR, PASSIVE, CERAMIC, MLCC")
    (attr smd)
    (fp_text reference "C95" (at 5.437 1.487 270) (layer "B.SilkS")
        (effects (font (size 0.7 0.7) (thickness 0.15)) (justify left bottom mirror))
    )
    (fp_text value "C_100n_0402" (at -1.022927 -2.155213 270) (layer "B.Fab")
        (effects (font (size 0.7 0.7) (thickness 0.15)) (justify left bottom mirror))
    )
    (fp_text user "License: Apache-2.0" (at -0.939 -5.799 270) (layer "B.Fab") hide
        (effects (font (size 0.7 0.7) (thickness 0.15)) (justify left bottom mirror))
    )
    (fp_text user "${REFERENCE}" (at -0.939 -4.599 270) (layer "B.Fab") hide
        (effects (font (size 0.7 0.7) (thickness 0.15)) (justify left bottom mirror))
    )
    (fp_text user "Author: Antmicro" (at -0.939 -3.399 270) (layer "B.Fab") hide
        (effects (font (size 0.7 0.7) (thickness 0.15)) (justify left bottom mirror))
    )
    (fp_rect (start -0.925 0.47) (end 0.925 -0.47)
      (stroke (width 0.05) (type default)) (fill none) (layer "B.CrtYd"))
    (fp_line (start -0.494 -0.248) (end -0.494 0.25)
      (stroke (width 0.15) (type solid)) (layer "B.Fab"))
    (fp_line (start -0.494 0.25) (end 0.504 0.25)
      (stroke (width 0.15) (type solid)) (layer "B.Fab"))
    (fp_line (start 0.504 -0.248) (end -0.494 -0.248)
      (stroke (width 0.15) (type solid)) (layer "B.Fab"))
    (fp_line (start 0.504 0.25) (end 0.504 -0.248)
      (stroke (width 0.15) (type solid)) (layer "B.Fab"))
    (pad "1" smd roundrect (at -0.48 0 90) (size 0.59 0.64) (layers "B.Cu" "B.Paste" "B.Mask") (roundrect_rratio 0.25)
      (net 1 "GND") (pintype "passive"))
    (pad "2" smd roundrect (at 0.48 0 90) (size 0.59 0.64) (layers "B.Cu" "B.Paste" "B.Mask") (roundrect_rratio 0.25)
      (net 2 "3V3_SYS") (pintype "passive"))
  )
	(footprint "antmicro-footprints:R_0402_1005Metric" (layer "B.Cu")
    (at 128.19 77.84)
    (descr "Resistor SMD 0402")
    (tags "resistor SMD 0402")
    (property "Author" "Antmicro")
    (property "License" "Apache-2.0")
    (property "MPN" "CR0402-FX-1002GLF")
    (property "Manufacturer" "Bourns")
    (property "Sheetfile" "tb.kicad_sch")
    (property "Sheetname" "TB Controller")
    (property "Tolerance" "1%")
    (property "Val" "10k")
    (property "ki_description" "SMD Chip Resistor, 10 kohm, ± 1%, 62.5 mW, 0402 [1005 Metric], Thick Film, General Purpose")
    (property "ki_keywords" "0402, SMT, RESISTOR, PASSIVE")
    (attr smd)
    (fp_text reference "R56" (at -0.936 0.519 180) (layer "B.SilkS")
        (effects (font (size 0.7 0.7) (thickness 0.15)) (justify left bottom mirror))
    )
    (fp_text value "R_10k_0402" (at -1.011843 -1.772047 180) (layer "B.Fab")
        (effects (font (size 0.7 0.7) (thickness 0.15)) (justify left bottom mirror))
    )
    (fp_text user "${REFERENCE}" (at -0.95 -3.168 180) (layer "B.Fab") hide
        (effects (font (size 0.7 0.7) (thickness 0.15)) (justify left bottom mirror))
    )
    (fp_text user "Author: Antmicro" (at -0.95 -4.169 180) (layer "B.Fab") hide
        (effects (font (size 0.7 0.7) (thickness 0.15)) (justify left bottom mirror))
    )
    (fp_text user "License: Apache-2.0" (at -0.95 -5.169 180) (layer "B.Fab") hide
        (effects (font (size 0.7 0.7) (thickness 0.15)) (justify left bottom mirror))
    )
    (fp_rect (start -0.925 0.47) (end 0.925 -0.47)
      (stroke (width 0.05) (type default)) (fill none) (layer "B.CrtYd"))
    (fp_rect (start -0.5 0.25) (end 0.5 -0.25)
      (stroke (width 0.15) (type solid)) (fill none) (layer "B.Fab"))
    (pad "1" smd roundrect (at -0.48 0) (size 0.59 0.64) (layers "B.Cu" "B.Paste" "B.Mask") (roundrect_rratio 0.25)
      (net 2 "3V3_SYS") (pintype "passive"))
    (pad "2" smd roundrect (at 0.48 0) (size 0.59 0.64) (layers "B.Cu" "B.Paste" "B.Mask") (roundrect_rratio 0.25)
      (net 170 "Net-(U4B-PCIE_CLKREQ_N)") (pintype "passive"))
  )
	(footprint "antmicro-footprints:R_0402_1005Metric" (layer "B.Cu")
    (at 115.440001 63.675 90)
    (descr "Resistor SMD 0402")
    (tags "resistor SMD 0402")
    (property "Author" "Antmicro")
    (property "License" "Apache-2.0")
    (property "MPN" "CR0402-FX-1002GLF")
    (property "Manufacturer" "Bourns")
    (property "Sheetfile" "power.kicad_sch")
    (property "Sheetname" "Power")
    (property "Tolerance" "1%")
    (property "Val" "10k")
    (property "ki_description" "SMD Chip Resistor, 10 kohm, ± 1%, 62.5 mW, 0402 [1005 Metric], Thick Film, General Purpose")
    (property "ki_keywords" "0402, SMT, RESISTOR, PASSIVE")
    (attr smd)
    (fp_text reference "R11" (at 3.223 0.383999 270) (layer "B.SilkS")
        (effects (font (size 0.7 0.7) (thickness 0.15)) (justify left bottom mirror))
    )
    (fp_text value "R_10k_0402" (at -1.011843 -1.772047 270) (layer "B.Fab")
        (effects (font (size 0.7 0.7) (thickness 0.15)) (justify left bottom mirror))
    )
    (fp_text user "License: Apache-2.0" (at -0.95 -5.169 270) (layer "B.Fab") hide
        (effects (font (size 0.7 0.7) (thickness 0.15)) (justify left bottom mirror))
    )
    (fp_text user "${REFERENCE}" (at -0.95 -3.168 270) (layer "B.Fab") hide
        (effects (font (size 0.7 0.7) (thickness 0.15)) (justify left bottom mirror))
    )
    (fp_text user "Author: Antmicro" (at -0.95 -4.169 270) (layer "B.Fab") hide
        (effects (font (size 0.7 0.7) (thickness 0.15)) (justify left bottom mirror))
    )
    (fp_rect (start -0.925 0.47) (end 0.925 -0.47)
      (stroke (width 0.05) (type default)) (fill none) (layer "B.CrtYd"))
    (fp_rect (start -0.5 0.25) (end 0.5 -0.25)
      (stroke (width 0.15) (type solid)) (fill none) (layer "B.Fab"))
    (pad "1" smd roundrect (at -0.48 0 90) (size 0.59 0.64) (layers "B.Cu" "B.Paste" "B.Mask") (roundrect_rratio 0.25)
      (net 1 "GND") (pintype "passive"))
    (pad "2" smd roundrect (at 0.48 0 90) (size 0.59 0.64) (layers "B.Cu" "B.Paste" "B.Mask") (roundrect_rratio 0.25)
      (net 119 "Net-(D1-C)") (pintype "passive"))
  )
	(footprint "antmicro-footprints:C_0402_1005Metric" (layer "B.Cu")
    (at 108.915 79.65 180)
    (descr "Capacitor SMD 0402")
    (tags "capacitor SMD 0402")
    (property "Author" "Antmicro")
    (property "Dielectric" "X5R")
    (property "License" "Apache-2.0")
    (property "MPN" "GRM155R61H104KE14D")
    (property "Manufacturer" "Murata")
    (property "Sheetfile" "power.kicad_sch")
    (property "Sheetname" "Power")
    (property "Val" "100n")
    (property "Voltage" "50V")
    (property "ki_description" "SMD Multilayer Ceramic Capacitor, 0.1 µF, 50 V, 0402 [1005 Metric], ± 10%, X5R, GRM Series")
    (property "ki_keywords" "0402, SMT, CAPACITOR, PASSIVE, CERAMIC, MLCC")
    (attr smd)
    (fp_text reference "C26" (at -1.067 5.736) (layer "B.SilkS")
        (effects (font (size 0.7 0.7) (thickness 0.15)) (justify left bottom mirror))
    )
    (fp_text value "C_100n_0402" (at -1.022927 -2.155213) (layer "B.Fab")
        (effects (font (size 0.7 0.7) (thickness 0.15)) (justify left bottom mirror))
    )
    (fp_text user "Author: Antmicro" (at -0.939 -3.399) (layer "B.Fab") hide
        (effects (font (size 0.7 0.7) (thickness 0.15)) (justify left bottom mirror))
    )
    (fp_text user "${REFERENCE}" (at -0.939 -4.599) (layer "B.Fab") hide
        (effects (font (size 0.7 0.7) (thickness 0.15)) (justify left bottom mirror))
    )
    (fp_text user "License: Apache-2.0" (at -0.939 -5.799) (layer "B.Fab") hide
        (effects (font (size 0.7 0.7) (thickness 0.15)) (justify left bottom mirror))
    )
    (fp_rect (start -0.925 0.47) (end 0.925 -0.47)
      (stroke (width 0.05) (type default)) (fill none) (layer "B.CrtYd"))
    (fp_line (start -0.494 -0.248) (end -0.494 0.25)
      (stroke (width 0.15) (type solid)) (layer "B.Fab"))
    (fp_line (start -0.494 0.25) (end 0.504 0.25)
      (stroke (width 0.15) (type solid)) (layer "B.Fab"))
    (fp_line (start 0.504 -0.248) (end -0.494 -0.248)
      (stroke (width 0.15) (type solid)) (layer "B.Fab"))
    (fp_line (start 0.504 0.25) (end 0.504 -0.248)
      (stroke (width 0.15) (type solid)) (layer "B.Fab"))
    (pad "1" smd roundrect (at -0.48 0 180) (size 0.59 0.64) (layers "B.Cu" "B.Paste" "B.Mask") (roundrect_rratio 0.25)
      (net 93 "Net-(U1-BST1)") (pintype "passive"))
    (pad "2" smd roundrect (at 0.48 0 180) (size 0.59 0.64) (layers "B.Cu" "B.Paste" "B.Mask") (roundrect_rratio 0.25)
      (net 4 "Net-(C26-Pad2)") (pintype "passive"))
  )
	(footprint "antmicro-footprints:C_0402_1005Metric" (layer "B.Cu")
    (at 159.91 65.47 -90)
    (descr "Capacitor SMD 0402")
    (tags "capacitor SMD 0402")
    (property "Author" "Antmicro")
    (property "Dielectric" "")
    (property "License" "Apache-2.0")
    (property "MPN" "04025C221JAT2A")
    (property "Manufacturer" "KYOCERA AVX")
    (property "Sheetfile" "power.kicad_sch")
    (property "Sheetname" "Power")
    (property "Val" "220p")
    (property "Voltage" "")
    (property "ki_description" "SMD Multilayer Ceramic Capacitor, 220 pF, 50 V, 0402 [1005 Metric], ± 10%, X7R, MC")
    (property "ki_keywords" "0402, SMT, CAPACITOR, PASSIVE")
    (attr smd)
    (fp_text reference "C45" (at -1.033214 -2.376506 90) (layer "B.SilkS")
        (effects (font (size 0.7 0.7) (thickness 0.15)) (justify left bottom mirror))
    )
    (fp_text value "C_220p_0402" (at -1.022927 -2.155213 90) (layer "B.Fab")
        (effects (font (size 0.7 0.7) (thickness 0.15)) (justify left bottom mirror))
    )
    (fp_text user "Author: Antmicro" (at -0.939 -3.399 90) (layer "B.Fab") hide
        (effects (font (size 0.7 0.7) (thickness 0.15)) (justify left bottom mirror))
    )
    (fp_text user "${REFERENCE}" (at -0.939 -4.599 90) (layer "B.Fab") hide
        (effects (font (size 0.7 0.7) (thickness 0.15)) (justify left bottom mirror))
    )
    (fp_text user "License: Apache-2.0" (at -0.939 -5.799 90) (layer "B.Fab") hide
        (effects (font (size 0.7 0.7) (thickness 0.15)) (justify left bottom mirror))
    )
    (fp_rect (start -0.925 0.47) (end 0.925 -0.47)
      (stroke (width 0.05) (type default)) (fill none) (layer "B.CrtYd"))
    (fp_line (start -0.494 -0.248) (end -0.494 0.25)
      (stroke (width 0.15) (type solid)) (layer "B.Fab"))
    (fp_line (start -0.494 0.25) (end 0.504 0.25)
      (stroke (width 0.15) (type solid)) (layer "B.Fab"))
    (fp_line (start 0.504 -0.248) (end -0.494 -0.248)
      (stroke (width 0.15) (type solid)) (layer "B.Fab"))
    (fp_line (start 0.504 0.25) (end 0.504 -0.248)
      (stroke (width 0.15) (type solid)) (layer "B.Fab"))
    (pad "1" smd roundrect (at -0.48 0 270) (size 0.59 0.64) (layers "B.Cu" "B.Paste" "B.Mask") (roundrect_rratio 0.25)
      (net 1 "GND") (pintype "passive"))
    (pad "2" smd roundrect (at 0.48 0 270) (size 0.59 0.64) (layers "B.Cu" "B.Paste" "B.Mask") (roundrect_rratio 0.25)
      (net 10 "CC2") (pintype "passive"))
  )
)
